# BASEBOARD_FAB2 (Tioga Pass) — schematic netlist excerpt (pin names and nets, part order shuffled) for the footprints in the layout excerpt that follows; sources: Cadence DE-HDL packaged netlist, KiCad conversion of Wiwynn_Tioga_Pass_MB.brd

C5G67  CAP_A  22.0UF 4V 20% X6S  pkg 0603V  page 242 : A = PVDDQ_DEF ; B = GND
C3N20  CAP_A  1.0UF 6.3V 10% X6S  pkg 0402V  page 132 : A = PVNN_PCH_STBY ; B = GND

U2R1  TC7PZ14FU-GP  pkg DISCRET-GA1  page 157
  \1a\  = FP_NMI_BTN
  GND  = GND
  \2a\  = FP_NMI_BTN_OUT_N
  \2y\  = FP_NMI_BTN
  VCC  = P3V3_STBY
  \1y\  = FP_NMI_BTN_R_N

(kicad_pcb
	(version 20260206)
	(generator "pcbnew")
	(generator_version "10.0")
	(general
		(thickness 1.6)
		(legacy_teardrops no)
	)
	(paper "A4")
	(title_block
		(title "Wiwynn_Tioga_Pass_MB.brd")
		(comment 1 "Tioga Pass / footprints 2899-2901 of 4770")
	)
	(layers
		(0 "F.Cu" signal "TOP")
		(4 "In1.Cu" signal "L2GND")
		(6 "In2.Cu" signal "L3")
		(8 "In3.Cu" signal "L4GND")
		(10 "In4.Cu" signal "L5")
		(12 "In5.Cu" signal "L6GND")
		(14 "In6.Cu" signal "L7VCC")
		(16 "In7.Cu" signal "L8VCC")
		(18 "In8.Cu" signal "L9GND")
		(20 "In9.Cu" signal "L10")
		(22 "In10.Cu" signal "L11GND")
		(24 "In11.Cu" signal "L12")
		(26 "In12.Cu" signal "L13GND")
		(2 "B.Cu" signal "BOTTOM")
		(9 "F.Adhes" user "F.Adhesive")
		(11 "B.Adhes" user "B.Adhesive")
		(13 "F.Paste" user "Package Geometry/Pastemask Top")
		(15 "B.Paste" user "Package Geometry/Pastemask Bottom")
		(5 "F.SilkS" user "Ref Des/Silkscreen Top")
		(7 "B.SilkS" user "Ref Des/Silkscreen Bottom")
		(1 "F.Mask" user "Board Geometry/Soldermask Top")
		(3 "B.Mask" user "Board Geometry/Soldermask Bottom")
		(17 "Dwgs.User" user "User.Drawings")
		(19 "Cmts.User" user "User.Comments")
		(21 "Eco1.User" user "User.Eco1")
		(23 "Eco2.User" user "User.Eco2")
		(25 "Edge.Cuts" user "Board Geometry/Outline")
		(27 "Margin" user)
		(31 "F.CrtYd" user "Package Geometry/Place Bound Top")
		(29 "B.CrtYd" user "Package Geometry/Place Bound Bottom")
		(35 "F.Fab" user "Ref Des/Assembly Top")
		(33 "B.Fab" user "Ref Des/Assembly Bottom")
	)
	(footprint ""
		(layer "B.Cu")
		(at 382.93675 -106.25455)
		(property "Reference" "C3N20"
			(at 0 0 0)
			(layer "B.SilkS")
			(hide yes)
			(effects
				(font
					(size 1.27 1.27)
				)
				(justify mirror)
			)
		)
		(property "Value" ""
			(at 0 0 0)
			(layer "B.Fab")
			(effects
				(font
					(size 1.27 1.27)
				)
				(justify mirror)
			)
		)
		(duplicate_pad_numbers_are_jumpers no)
		(fp_rect
			(start 0.2794 0.9144)
			(end -0.2794 -0.1143)
			(stroke
				(width 0)
				(type default)
			)
			(fill no)
			(layer "B.CrtYd")
		)
		(fp_line
			(start -0.2794 -0.1143)
			(end -0.2794 0.9144)
			(stroke
				(width 0.1)
				(type default)
			)
			(layer "B.Fab")
		)
		(fp_line
			(start -0.2794 0.9144)
			(end 0.2794 0.9144)
			(stroke
				(width 0.1)
				(type default)
			)
			(layer "B.Fab")
		)
		(fp_line
			(start 0.2794 -0.1143)
			(end -0.2794 -0.1143)
			(stroke
				(width 0.1)
				(type default)
			)
			(layer "B.Fab")
		)
		(fp_line
			(start 0.2794 0.9144)
			(end 0.2794 -0.1143)
			(stroke
				(width 0.1)
				(type default)
			)
			(layer "B.Fab")
		)
		(pad "1" smd custom
			(at 0 0 270)
			(size 0.10414 0.10414)
			(layers "B.Cu" "B.Mask" "B.Paste")
			(net "PVNN_PCH_STBY")
			(options
				(clearance outline)
				(anchor circle)
			)
			(primitives
				(gr_poly
					(pts
						(xy -0.20828 -0.08636) (xy -0.20828 0.08636) (xy -0.08636 0.20828) (xy 0.086614 0.20828) (xy 0.20828 0.086614)
						(xy 0.20828 -0.08636) (xy 0.08636 -0.20828) (xy -0.08636 -0.20828)
					)
					(width 0)
					(fill yes)
				)
			)
		)
		(pad "2" smd custom
			(at 0 0.8001 270)
			(size 0.10414 0.10414)
			(layers "B.Cu" "B.Mask" "B.Paste")
			(net "GND")
			(options
				(clearance outline)
				(anchor circle)
			)
			(primitives
				(gr_poly
					(pts
						(xy -0.20828 -0.08636) (xy -0.20828 0.08636) (xy -0.08636 0.20828) (xy 0.086614 0.20828) (xy 0.20828 0.086614)
						(xy 0.20828 -0.08636) (xy 0.08636 -0.20828) (xy -0.08636 -0.20828)
					)
					(width 0)
					(fill yes)
				)
			)
		)
		(zone
			(layer "B.Cu")
			(hatch none 0.5)
			(connect_pads
				(clearance 0)
			)
			(min_thickness 0.25)
			(keepout
				(tracks not_allowed)
				(vias allowed)
				(pads allowed)
				(copperpour not_allowed)
				(footprints allowed)
			)
			(placement
				(enabled no)
				(sheetname "")
			)
			(fill
				(thermal_gap 0.5)
				(thermal_bridge_width 0.5)
				(island_removal_mode 0)
			)
			(polygon
				(pts
					(xy 383.02438 -106.045) (xy 383.02438 -105.664) (xy 382.84912 -105.664) (xy 382.848866 -106.045)
				)
			)
		)
		(zone
			(layer "B.Cu")
			(hatch none 0.5)
			(connect_pads
				(clearance 0)
			)
			(min_thickness 0.25)
			(keepout
				(tracks allowed)
				(vias not_allowed)
				(pads allowed)
				(copperpour not_allowed)
				(footprints allowed)
			)
			(placement
				(enabled no)
				(sheetname "")
			)
			(fill
				(thermal_gap 0.5)
				(thermal_bridge_width 0.5)
				(island_removal_mode 0)
			)
			(polygon
				(pts
					(xy 383.02438 -106.045) (xy 383.02438 -105.664) (xy 382.84912 -105.664) (xy 382.848866 -106.045)
				)
			)
		)
	)
	(footprint ""
		(layer "B.Cu")
		(at 410.3624 -14.097 90)
		(property "Reference" "U2R1"
			(at 0 0 90)
			(layer "B.SilkS")
			(hide yes)
			(effects
				(font
					(size 1.27 1.27)
				)
				(justify mirror)
			)
		)
		(property "Value" "*"
			(at 2.3622 -8.3185 90)
			(unlocked yes)
			(layer "B.Fab")
			(hide yes)
			(effects
				(font
					(size 1.27 1.016)
					(thickness 0.1524)
				)
				(justify mirror)
			)
		)
		(property "Device Type" "TC7PZ14FU-GP_DISCRET-GA1-TC7PZA"
			(at 2.3622 -10.2235 90)
			(unlocked yes)
			(layer "B.Fab")
			(hide yes)
			(effects
				(font
					(size 1.27 1.016)
					(thickness 0.1524)
				)
				(justify mirror)
			)
		)
		(duplicate_pad_numbers_are_jumpers no)
		(fp_line
			(start 1.4478 -1.7018)
			(end 1.4478 1.7018)
			(stroke
				(width 0.1524)
				(type default)
			)
			(layer "B.SilkS")
		)
		(fp_line
			(start -1.4478 -1.7018)
			(end 1.4478 -1.7018)
			(stroke
				(width 0.1524)
				(type default)
			)
			(layer "B.SilkS")
		)
		(fp_line
			(start 1.4478 1.7018)
			(end -1.4478 1.7018)
			(stroke
				(width 0.1524)
				(type default)
			)
			(layer "B.SilkS")
		)
		(fp_line
			(start -1.4478 1.7018)
			(end -1.4478 -1.7018)
			(stroke
				(width 0.1524)
				(type default)
			)
			(layer "B.SilkS")
		)
		(fp_line
			(start 1.5494 1.7907)
			(end 1.5494 0.8255)
			(stroke
				(width 0.3302)
				(type default)
			)
			(layer "B.SilkS")
		)
		(fp_line
			(start 0.5715 1.7907)
			(end 1.5494 1.7907)
			(stroke
				(width 0.3302)
				(type default)
			)
			(layer "B.SilkS")
		)
		(fp_poly
			(pts
				(xy 0.6604 1.7272) (xy 1.016 2.0828) (xy 0.3048 2.0828)
			)
			(stroke
				(width 0)
				(type default)
			)
			(fill yes)
			(layer "B.SilkS")
		)
		(fp_poly
			(pts
				(xy 1.524 -1.778) (xy -1.524 -1.778) (xy -1.524 1.778) (xy 1.524 1.778)
			)
			(stroke
				(width 0)
				(type default)
			)
			(fill no)
			(layer "B.CrtYd")
		)
		(fp_poly
			(pts
				(xy 1.524 -1.778) (xy -1.524 -1.778) (xy -1.524 1.778) (xy 1.524 1.778)
			)
			(stroke
				(width 0)
				(type default)
			)
			(fill no)
			(layer "B.Fab")
		)
		(pad "1" smd rect
			(at 0.65024 0.9398 270)
			(size 0.4064 1.016)
			(layers "B.Cu" "B.Mask" "B.Paste")
			(net "FP_NMI_BTN")
		)
		(pad "2" smd rect
			(at 0 0.9398 270)
			(size 0.4064 1.016)
			(layers "B.Cu" "B.Mask" "B.Paste")
			(net "GND")
		)
		(pad "3" smd rect
			(at -0.65024 0.9398 270)
			(size 0.4064 1.016)
			(layers "B.Cu" "B.Mask" "B.Paste")
			(net "FP_NMI_BTN_OUT_N")
		)
		(pad "4" smd rect
			(at -0.65024 -0.9398 270)
			(size 0.4064 1.016)
			(layers "B.Cu" "B.Mask" "B.Paste")
			(net "FP_NMI_BTN")
		)
		(pad "5" smd rect
			(at 0 -0.9398 270)
			(size 0.4064 1.016)
			(layers "B.Cu" "B.Mask" "B.Paste")
			(net "P3V3_STBY")
		)
		(pad "6" smd rect
			(at 0.65024 -0.9398 270)
			(size 0.4064 1.016)
			(layers "B.Cu" "B.Mask" "B.Paste")
			(net "FP_NMI_BTN_R_N")
		)
	)
	(footprint ""
		(layer "B.Cu")
		(at 253.392432 -140.208 90)
		(property "Reference" "C5G67"
			(at -1.14681 0.76708 180)
			(unlocked yes)
			(layer "B.SilkS")
			(effects
				(font
					(size 0.7874 0.5842)
					(thickness 0.1524)
				)
				(justify mirror)
			)
		)
		(property "Value" ""
			(at 0 0 90)
			(layer "B.Fab")
			(effects
				(font
					(size 1.27 1.27)
				)
				(justify mirror)
			)
		)
		(duplicate_pad_numbers_are_jumpers no)
		(fp_rect
			(start -0.4953 -0.2032)
			(end 0.4953 1.6002)
			(stroke
				(width 0)
				(type default)
			)
			(fill no)
			(layer "B.CrtYd")
		)
		(fp_line
			(start 0.4953 -0.2032)
			(end -0.4953 -0.2032)
			(stroke
				(width 0.1)
				(type default)
			)
			(layer "B.Fab")
		)
		(fp_line
			(start -0.4953 -0.2032)
			(end -0.4953 1.6002)
			(stroke
				(width 0.1)
				(type default)
			)
			(layer "B.Fab")
		)
		(fp_line
			(start 0.4953 1.6002)
			(end 0.4953 -0.2032)
			(stroke
				(width 0.1)
				(type default)
			)
			(layer "B.Fab")
		)
		(fp_line
			(start -0.4953 1.6002)
			(end 0.4953 1.6002)
			(stroke
				(width 0.1)
				(type default)
			)
			(layer "B.Fab")
		)
		(pad "1" smd rect
			(at 0 0 270)
			(size 0.762 0.889)
			(layers "B.Cu" "B.Mask" "B.Paste")
			(net "PVDDQ_DEF")
		)
		(pad "2" smd rect
			(at 0 1.397 270)
			(size 0.762 0.889)
			(layers "B.Cu" "B.Mask" "B.Paste")
			(net "GND")
		)
		(zone
			(layer "B.Cu")
			(hatch none 0.5)
			(connect_pads
				(clearance 0)
			)
			(min_thickness 0.25)
			(keepout
				(tracks not_allowed)
				(vias allowed)
				(pads allowed)
				(copperpour not_allowed)
				(footprints allowed)
			)
			(placement
				(enabled no)
				(sheetname "")
			)
			(fill
				(thermal_gap 0.5)
				(thermal_bridge_width 0.5)
				(island_removal_mode 0)
			)
			(polygon
				(pts
					(xy 253.836932 -139.827) (xy 254.344932 -139.827) (xy 254.344932 -140.589) (xy 253.836932 -140.589)
				)
			)
		)
	)
)
